(kicad_pcb
	(version 20240108)
	(generator "pcbnew")
	(generator_version "8.0")
	(general
		(thickness 1.62)
		(legacy_teardrops no)
	)
	(paper "A4")
	(title_block
		(title "Jetson Orin Baseboard")
		(date "2025-03-12")
		(rev "1.3.4")
		(company "Antmicro Ltd")
		(comment 1 "www.antmicro.com")
		(comment 9 "footprints 313-317 of 677")
	)
	(layers
		(0 "F.Cu" signal)
		(1 "In1.Cu" signal)
		(2 "In2.Cu" signal)
		(3 "In3.Cu" signal)
		(4 "In4.Cu" jumper)
		(5 "In5.Cu" signal)
		(6 "In6.Cu" signal)
		(31 "B.Cu" signal)
		(32 "B.Adhes" user "B.Adhesive")
		(33 "F.Adhes" user "F.Adhesive")
		(34 "B.Paste" user)
		(35 "F.Paste" user)
		(36 "B.SilkS" user "B.Silkscreen")
		(37 "F.SilkS" user "F.Silkscreen")
		(38 "B.Mask" user)
		(39 "F.Mask" user)
		(40 "Dwgs.User" user "User.Drawings")
		(41 "Cmts.User" user "User.Comments")
		(42 "Eco1.User" user "User.Eco1")
		(43 "Eco2.User" user "User.Eco2")
		(44 "Edge.Cuts" user)
		(45 "Margin" user)
		(46 "B.CrtYd" user "B.Courtyard")
		(47 "F.CrtYd" user "F.Courtyard")
		(48 "B.Fab" user)
		(49 "F.Fab" user)
	)
	(footprint "antmicro-footprints:R_0402_1005Metric"
		(layer "B.Cu")
		(at 112.4 103.1)
		(descr "Resistor SMD 0402")
		(tags "resistor SMD 0402")
		(property "Reference" "R135"
			(at 3.68 0.35 180)
			(layer "B.SilkS")
			(effects
				(font
					(size 0.7 0.7)
					(thickness 0.15)
				)
				(justify left bottom mirror)
			)
		)
		(property "Value" "R_10k_0402"
			(at 0 -1.4 180)
			(layer "B.Fab")
			(effects
				(font
					(size 0.7 0.7)
					(thickness 0.15)
				)
				(justify left bottom mirror)
			)
		)
		(property "Footprint" "antmicro-footprints:R_0402_1005Metric"
			(at 0 0 0)
			(layer "F.Fab")
			(hide yes)
			(effects
				(font
					(size 1.27 1.27)
					(thickness 0.15)
				)
			)
		)
		(property "Datasheet" "https://www.bourns.com/docs/product-datasheets/cr.pdf"
			(at 0 0 0)
			(layer "F.Fab")
			(hide yes)
			(effects
				(font
					(size 1.27 1.27)
					(thickness 0.15)
				)
			)
		)
		(property "Author" "Antmicro"
			(at 0 0 0)
			(layer "B.Fab")
			(hide yes)
			(effects
				(font
					(size 1 1)
					(thickness 0.15)
				)
				(justify mirror)
			)
		)
		(property "License" "Apache-2.0"
			(at 0 0 0)
			(layer "B.Fab")
			(hide yes)
			(effects
				(font
					(size 1 1)
					(thickness 0.15)
				)
				(justify mirror)
			)
		)
		(property "MPN" "CR0402-FX-1002GLF"
			(at 0 0 0)
			(layer "B.Fab")
			(hide yes)
			(effects
				(font
					(size 1 1)
					(thickness 0.15)
				)
				(justify mirror)
			)
		)
		(property "Manufacturer" "Bourns"
			(at 0 0 0)
			(layer "B.Fab")
			(hide yes)
			(effects
				(font
					(size 1 1)
					(thickness 0.15)
				)
				(justify mirror)
			)
		)
		(property "Tolerance" "1%"
			(at 0 0 0)
			(layer "B.Fab")
			(hide yes)
			(effects
				(font
					(size 1 1)
					(thickness 0.15)
				)
				(justify mirror)
			)
		)
		(property "Val" "10k"
			(at 0 0 0)
			(layer "B.Fab")
			(hide yes)
			(effects
				(font
					(size 1 1)
					(thickness 0.15)
				)
				(justify mirror)
			)
		)
		(sheetname "USB3")
		(sheetfile "usb3.kicad_sch")
		(attr smd)
		(fp_rect
			(start -0.925 0.47)
			(end 0.925 -0.47)
			(stroke
				(width 0.05)
				(type default)
			)
			(fill none)
			(layer "B.CrtYd")
		)
		(fp_rect
			(start -0.5 0.25)
			(end 0.5 -0.25)
			(stroke
				(width 0.15)
				(type solid)
			)
			(fill none)
			(layer "B.Fab")
		)
		(fp_text user "${REFERENCE}"
			(at -0.95 -3.168 180)
			(layer "B.Fab")
			(hide yes)
			(effects
				(font
					(size 0.7 0.7)
					(thickness 0.15)
				)
				(justify left bottom mirror)
			)
		)
		(fp_text user "Author: Antmicro"
			(at -0.95 -4.169 180)
			(layer "B.Fab")
			(hide yes)
			(effects
				(font
					(size 0.7 0.7)
					(thickness 0.15)
				)
				(justify left bottom mirror)
			)
		)
		(fp_text user "License: Apache-2.0"
			(at -0.95 -5.169 180)
			(layer "B.Fab")
			(hide yes)
			(effects
				(font
					(size 0.7 0.7)
					(thickness 0.15)
				)
				(justify left bottom mirror)
			)
		)
		(pad "1" smd roundrect
			(at -0.48 0)
			(size 0.59 0.64)
			(layers "B.Cu" "B.Paste" "B.Mask")
			(roundrect_rratio 0.25)
			(net 391 "/USB3/USBC1_FAULT_N")
			(pintype "passive")
		)
		(pad "2" smd roundrect
			(at 0.48 0)
			(size 0.59 0.64)
			(layers "B.Cu" "B.Paste" "B.Mask")
			(roundrect_rratio 0.25)
			(net 99 "+5V")
			(pintype "passive")
		)
	)
	(footprint "antmicro-footprints:C_0402_1005Metric"
		(layer "B.Cu")
		(at 98.6 75.25)
		(descr "Capacitor SMD 0402")
		(tags "capacitor SMD 0402")
		(property "Reference" "C98"
			(at 0.95 1.36 180)
			(layer "B.SilkS")
			(effects
				(font
					(size 0.7 0.7)
					(thickness 0.15)
				)
				(justify left bottom mirror)
			)
		)
		(property "Value" "C_1u_0402"
			(at 0 -1.4 180)
			(layer "B.Fab")
			(effects
				(font
					(size 0.7 0.7)
					(thickness 0.15)
				)
				(justify left bottom mirror)
			)
		)
		(property "Footprint" "antmicro-footprints:C_0402_1005Metric"
			(at 0 0 0)
			(layer "F.Fab")
			(hide yes)
			(effects
				(font
					(size 1.27 1.27)
					(thickness 0.15)
				)
			)
		)
		(property "Datasheet" "https://product.tdk.com/en/search/capacitor/ceramic/mlcc/info?part_no=C1005X6S1A105K050BC"
			(at 0 0 0)
			(layer "F.Fab")
			(hide yes)
			(effects
				(font
					(size 1.27 1.27)
					(thickness 0.15)
				)
			)
		)
		(property "Author" "Antmicro"
			(at 0 0 0)
			(layer "B.Fab")
			(hide yes)
			(effects
				(font
					(size 1 1)
					(thickness 0.15)
				)
				(justify mirror)
			)
		)
		(property "Dielectric" ""
			(at 0 0 0)
			(layer "B.Fab")
			(hide yes)
			(effects
				(font
					(size 1 1)
					(thickness 0.15)
				)
				(justify mirror)
			)
		)
		(property "License" "Apache-2.0"
			(at 0 0 0)
			(layer "B.Fab")
			(hide yes)
			(effects
				(font
					(size 1 1)
					(thickness 0.15)
				)
				(justify mirror)
			)
		)
		(property "MPN" "C1005X6S1A105K050BC"
			(at 0 0 0)
			(layer "B.Fab")
			(hide yes)
			(effects
				(font
					(size 1 1)
					(thickness 0.15)
				)
				(justify mirror)
			)
		)
		(property "Manufacturer" "TDK"
			(at 0 0 0)
			(layer "B.Fab")
			(hide yes)
			(effects
				(font
					(size 1 1)
					(thickness 0.15)
				)
				(justify mirror)
			)
		)
		(property "Val" "1u"
			(at 0 0 0)
			(layer "B.Fab")
			(hide yes)
			(effects
				(font
					(size 1 1)
					(thickness 0.15)
				)
				(justify mirror)
			)
		)
		(property "Voltage" ""
			(at 0 0 0)
			(layer "B.Fab")
			(hide yes)
			(effects
				(font
					(size 1 1)
					(thickness 0.15)
				)
				(justify mirror)
			)
		)
		(sheetname "CSI")
		(sheetfile "csi.kicad_sch")
		(attr smd)
		(fp_rect
			(start -0.925 0.47)
			(end 0.925 -0.47)
			(stroke
				(width 0.05)
				(type default)
			)
			(fill none)
			(layer "B.CrtYd")
		)
		(fp_line
			(start -0.494 -0.248)
			(end 0.504 -0.248)
			(stroke
				(width 0.15)
				(type solid)
			)
			(layer "B.Fab")
		)
		(fp_line
			(start -0.494 0.25)
			(end -0.494 -0.248)
			(stroke
				(width 0.15)
				(type solid)
			)
			(layer "B.Fab")
		)
		(fp_line
			(start 0.504 -0.248)
			(end 0.504 0.25)
			(stroke
				(width 0.15)
				(type solid)
			)
			(layer "B.Fab")
		)
		(fp_line
			(start 0.504 0.25)
			(end -0.494 0.25)
			(stroke
				(width 0.15)
				(type solid)
			)
			(layer "B.Fab")
		)
		(fp_text user "License: Apache-2.0"
			(at -0.932 -5.17 180)
			(layer "B.Fab")
			(hide yes)
			(effects
				(font
					(size 0.7 0.7)
					(thickness 0.15)
				)
				(justify left bottom mirror)
			)
		)
		(fp_text user "Author: Antmicro"
			(at -0.932 -4.17 180)
			(layer "B.Fab")
			(hide yes)
			(effects
				(font
					(size 0.7 0.7)
					(thickness 0.15)
				)
				(justify left bottom mirror)
			)
		)
		(fp_text user "${REFERENCE}"
			(at -0.932 -3.168 180)
			(layer "B.Fab")
			(hide yes)
			(effects
				(font
					(size 0.7 0.7)
					(thickness 0.15)
				)
				(justify left bottom mirror)
			)
		)
		(pad "1" smd roundrect
			(at -0.48 0)
			(size 0.59 0.64)
			(layers "B.Cu" "B.Paste" "B.Mask")
			(roundrect_rratio 0.25)
			(net 1 "GND")
			(pintype "passive")
		)
		(pad "2" smd roundrect
			(at 0.48 0)
			(size 0.59 0.64)
			(layers "B.Cu" "B.Paste" "B.Mask")
			(roundrect_rratio 0.25)
			(net 110 "/CSI/CSIB_3V3")
			(pintype "passive")
		)
	)
	(footprint "antmicro-footprints:R_0402_1005Metric"
		(layer "B.Cu")
		(at 135.8 99.4)
		(descr "Resistor SMD 0402")
		(tags "resistor SMD 0402")
		(property "Reference" "R11"
			(at -0.75 0.45 180)
			(layer "B.SilkS")
			(effects
				(font
					(size 0.7 0.7)
					(thickness 0.15)
				)
				(justify left bottom mirror)
			)
		)
		(property "Value" "R_0R_0402"
			(at 0 -1.4 180)
			(layer "B.Fab")
			(effects
				(font
					(size 0.7 0.7)
					(thickness 0.15)
				)
				(justify left bottom mirror)
			)
		)
		(property "Footprint" "antmicro-footprints:R_0402_1005Metric"
			(at 0 0 0)
			(layer "F.Fab")
			(hide yes)
			(effects
				(font
					(size 1.27 1.27)
					(thickness 0.15)
				)
			)
		)
		(property "Datasheet" "https://industrial.panasonic.com/cdbs/www-data/pdf/RDA0000/AOA0000C301.pdf"
			(at 0 0 0)
			(layer "F.Fab")
			(hide yes)
			(effects
				(font
					(size 1.27 1.27)
					(thickness 0.15)
				)
			)
		)
		(property "Author" "Antmicro"
			(at 0 0 0)
			(layer "B.Fab")
			(hide yes)
			(effects
				(font
					(size 1 1)
					(thickness 0.15)
				)
				(justify mirror)
			)
		)
		(property "Current" "1A"
			(at 0 0 0)
			(layer "B.Fab")
			(hide yes)
			(effects
				(font
					(size 1 1)
					(thickness 0.15)
				)
				(justify mirror)
			)
		)
		(property "License" "Apache-2.0"
			(at 0 0 0)
			(layer "B.Fab")
			(hide yes)
			(effects
				(font
					(size 1 1)
					(thickness 0.15)
				)
				(justify mirror)
			)
		)
		(property "MPN" "ERJ2GE0R00X"
			(at 0 0 0)
			(layer "B.Fab")
			(hide yes)
			(effects
				(font
					(size 1 1)
					(thickness 0.15)
				)
				(justify mirror)
			)
		)
		(property "Manufacturer" "Panasonic"
			(at 0 0 0)
			(layer "B.Fab")
			(hide yes)
			(effects
				(font
					(size 1 1)
					(thickness 0.15)
				)
				(justify mirror)
			)
		)
		(property "Tolerance" ""
			(at 0 0 0)
			(layer "B.Fab")
			(hide yes)
			(effects
				(font
					(size 1 1)
					(thickness 0.15)
				)
				(justify mirror)
			)
		)
		(property "Val" "0R"
			(at 0 0 0)
			(layer "B.Fab")
			(hide yes)
			(effects
				(font
					(size 1 1)
					(thickness 0.15)
				)
				(justify mirror)
			)
		)
		(sheetname "SoM")
		(sheetfile "som.kicad_sch")
		(attr smd)
		(fp_rect
			(start -0.925 0.47)
			(end 0.925 -0.47)
			(stroke
				(width 0.05)
				(type default)
			)
			(fill none)
			(layer "B.CrtYd")
		)
		(fp_rect
			(start -0.5 0.25)
			(end 0.5 -0.25)
			(stroke
				(width 0.15)
				(type solid)
			)
			(fill none)
			(layer "B.Fab")
		)
		(fp_text user "Author: Antmicro"
			(at -0.95 -4.169 180)
			(layer "B.Fab")
			(hide yes)
			(effects
				(font
					(size 0.7 0.7)
					(thickness 0.15)
				)
				(justify left bottom mirror)
			)
		)
		(fp_text user "License: Apache-2.0"
			(at -0.95 -5.169 180)
			(layer "B.Fab")
			(hide yes)
			(effects
				(font
					(size 0.7 0.7)
					(thickness 0.15)
				)
				(justify left bottom mirror)
			)
		)
		(fp_text user "${REFERENCE}"
			(at -0.95 -3.168 180)
			(layer "B.Fab")
			(hide yes)
			(effects
				(font
					(size 0.7 0.7)
					(thickness 0.15)
				)
				(justify left bottom mirror)
			)
		)
		(pad "1" smd roundrect
			(at -0.48 0)
			(size 0.59 0.64)
			(layers "B.Cu" "B.Paste" "B.Mask")
			(roundrect_rratio 0.25)
			(net 745 "Net-(J15B-CAM1_PWDN)")
			(pintype "passive")
		)
		(pad "2" smd roundrect
			(at 0.48 0)
			(size 0.59 0.64)
			(layers "B.Cu" "B.Paste" "B.Mask")
			(roundrect_rratio 0.25)
			(net 219 "VSYNC_CAM1")
			(pintype "passive")
		)
	)
	(footprint "antmicro-footprints:R_0402_1005Metric"
		(layer "B.Cu")
		(at 71.8 100.95 180)
		(descr "Resistor SMD 0402")
		(tags "resistor SMD 0402")
		(property "Reference" "R41"
			(at -0.72 1.54 0)
			(layer "B.SilkS")
			(effects
				(font
					(size 0.7 0.7)
					(thickness 0.15)
				)
				(justify left bottom mirror)
			)
		)
		(property "Value" "R_0R_0402"
			(at 0 -1.4 0)
			(layer "B.Fab")
			(effects
				(font
					(size 0.7 0.7)
					(thickness 0.15)
				)
				(justify left bottom mirror)
			)
		)
		(property "Footprint" "antmicro-footprints:R_0402_1005Metric"
			(at 0 0 180)
			(layer "F.Fab")
			(hide yes)
			(effects
				(font
					(size 1.27 1.27)
					(thickness 0.15)
				)
			)
		)
		(property "Datasheet" "https://industrial.panasonic.com/cdbs/www-data/pdf/RDA0000/AOA0000C301.pdf"
			(at 0 0 180)
			(layer "F.Fab")
			(hide yes)
			(effects
				(font
					(size 1.27 1.27)
					(thickness 0.15)
				)
			)
		)
		(property "Author" "Antmicro"
			(at 143.6 201.9 0)
			(layer "B.Fab")
			(hide yes)
			(effects
				(font
					(size 1 1)
					(thickness 0.15)
				)
				(justify mirror)
			)
		)
		(property "Current" "1A"
			(at 143.6 201.9 0)
			(layer "B.Fab")
			(hide yes)
			(effects
				(font
					(size 1 1)
					(thickness 0.15)
				)
				(justify mirror)
			)
		)
		(property "License" "Apache-2.0"
			(at 143.6 201.9 0)
			(layer "B.Fab")
			(hide yes)
			(effects
				(font
					(size 1 1)
					(thickness 0.15)
				)
				(justify mirror)
			)
		)
		(property "MPN" "ERJ2GE0R00X"
			(at 143.6 201.9 0)
			(layer "B.Fab")
			(hide yes)
			(effects
				(font
					(size 1 1)
					(thickness 0.15)
				)
				(justify mirror)
			)
		)
		(property "Manufacturer" "Panasonic"
			(at 143.6 201.9 0)
			(layer "B.Fab")
			(hide yes)
			(effects
				(font
					(size 1 1)
					(thickness 0.15)
				)
				(justify mirror)
			)
		)
		(property "Tolerance" ""
			(at 143.6 201.9 0)
			(layer "B.Fab")
			(hide yes)
			(effects
				(font
					(size 1 1)
					(thickness 0.15)
				)
				(justify mirror)
			)
		)
		(property "Val" "0R"
			(at 143.6 201.9 0)
			(layer "B.Fab")
			(hide yes)
			(effects
				(font
					(size 1 1)
					(thickness 0.15)
				)
				(justify mirror)
			)
		)
		(sheetname "USB Debug, DP")
		(sheetfile "usb.kicad_sch")
		(attr smd)
		(fp_rect
			(start -0.925 0.47)
			(end 0.925 -0.47)
			(stroke
				(width 0.05)
				(type default)
			)
			(fill none)
			(layer "B.CrtYd")
		)
		(fp_rect
			(start -0.5 0.25)
			(end 0.5 -0.25)
			(stroke
				(width 0.15)
				(type solid)
			)
			(fill none)
			(layer "B.Fab")
		)
		(fp_text user "License: Apache-2.0"
			(at -0.95 -5.169 0)
			(layer "B.Fab")
			(hide yes)
			(effects
				(font
					(size 0.7 0.7)
					(thickness 0.15)
				)
				(justify left bottom mirror)
			)
		)
		(fp_text user "${REFERENCE}"
			(at -0.95 -3.168 0)
			(layer "B.Fab")
			(hide yes)
			(effects
				(font
					(size 0.7 0.7)
					(thickness 0.15)
				)
				(justify left bottom mirror)
			)
		)
		(fp_text user "Author: Antmicro"
			(at -0.95 -4.169 0)
			(layer "B.Fab")
			(hide yes)
			(effects
				(font
					(size 0.7 0.7)
					(thickness 0.15)
				)
				(justify left bottom mirror)
			)
		)
		(pad "1" smd roundrect
			(at -0.48 0 180)
			(size 0.59 0.64)
			(layers "B.Cu" "B.Paste" "B.Mask")
			(roundrect_rratio 0.25)
			(net 1 "GND")
			(pintype "passive")
		)
		(pad "2" smd roundrect
			(at 0.48 0 180)
			(size 0.59 0.64)
			(layers "B.Cu" "B.Paste" "B.Mask")
			(roundrect_rratio 0.25)
			(net 285 "/USB Debug, DP/PDC_RESET")
			(pintype "passive")
		)
	)
	(footprint "antmicro-footprints:C_0402_1005Metric"
		(layer "B.Cu")
		(at 95.55 93.95)
		(descr "Capacitor SMD 0402")
		(tags "capacitor SMD 0402")
		(property "Reference" "C135"
			(at 5.82 0.69 180)
			(layer "B.SilkS")
			(effects
				(font
					(size 0.7 0.7)
					(thickness 0.15)
				)
				(justify left bottom mirror)
			)
		)
		(property "Value" "C_100n_0402"
			(at 0 -1.4 180)
			(layer "B.Fab")
			(effects
				(font
					(size 0.7 0.7)
					(thickness 0.15)
				)
				(justify left bottom mirror)
			)
		)
		(property "Footprint" "antmicro-footprints:C_0402_1005Metric"
			(at 0 0 0)
			(layer "F.Fab")
			(hide yes)
			(effects
				(font
					(size 1.27 1.27)
					(thickness 0.15)
				)
			)
		)
		(property "Datasheet" "https://www.murata.com/products/productdetail?partno=GRM155R61H104KE14%23"
			(at 0 0 0)
			(layer "F.Fab")
			(hide yes)
			(effects
				(font
					(size 1.27 1.27)
					(thickness 0.15)
				)
			)
		)
		(property "Author" "Antmicro"
			(at 0 0 0)
			(layer "B.Fab")
			(hide yes)
			(effects
				(font
					(size 1 1)
					(thickness 0.15)
				)
				(justify mirror)
			)
		)
		(property "Dielectric" "X5R"
			(at 0 0 0)
			(layer "B.Fab")
			(hide yes)
			(effects
				(font
					(size 1 1)
					(thickness 0.15)
				)
				(justify mirror)
			)
		)
		(property "License" "Apache-2.0"
			(at 0 0 0)
			(layer "B.Fab")
			(hide yes)
			(effects
				(font
					(size 1 1)
					(thickness 0.15)
				)
				(justify mirror)
			)
		)
		(property "MPN" "GRM155R61H104KE14D"
			(at 0 0 0)
			(layer "B.Fab")
			(hide yes)
			(effects
				(font
					(size 1 1)
					(thickness 0.15)
				)
				(justify mirror)
			)
		)
		(property "Manufacturer" "Murata"
			(at 0 0 0)
			(layer "B.Fab")
			(hide yes)
			(effects
				(font
					(size 1 1)
					(thickness 0.15)
				)
				(justify mirror)
			)
		)
		(property "Val" "100n"
			(at 0 0 0)
			(layer "B.Fab")
			(hide yes)
			(effects
				(font
					(size 1 1)
					(thickness 0.15)
				)
				(justify mirror)
			)
		)
		(property "Voltage" "50V"
			(at 0 0 0)
			(layer "B.Fab")
			(hide yes)
			(effects
				(font
					(size 1 1)
					(thickness 0.15)
				)
				(justify mirror)
			)
		)
		(sheetname "HDMI")
		(sheetfile "hdmi.kicad_sch")
		(attr smd)
		(fp_rect
			(start -0.925 0.47)
			(end 0.925 -0.47)
			(stroke
				(width 0.05)
				(type default)
			)
			(fill none)
			(layer "B.CrtYd")
		)
		(fp_line
			(start -0.494 -0.248)
			(end 0.504 -0.248)
			(stroke
				(width 0.15)
				(type solid)
			)
			(layer "B.Fab")
		)
		(fp_line
			(start -0.494 0.25)
			(end -0.494 -0.248)
			(stroke
				(width 0.15)
				(type solid)
			)
			(layer "B.Fab")
		)
		(fp_line
			(start 0.504 -0.248)
			(end 0.504 0.25)
			(stroke
				(width 0.15)
				(type solid)
			)
			(layer "B.Fab")
		)
		(fp_line
			(start 0.504 0.25)
			(end -0.494 0.25)
			(stroke
				(width 0.15)
				(type solid)
			)
			(layer "B.Fab")
		)
		(fp_text user "Author: Antmicro"
			(at -0.932 -4.17 180)
			(layer "B.Fab")
			(hide yes)
			(effects
				(font
					(size 0.7 0.7)
					(thickness 0.15)
				)
				(justify left bottom mirror)
			)
		)
		(fp_text user "License: Apache-2.0"
			(at -0.932 -5.17 180)
			(layer "B.Fab")
			(hide yes)
			(effects
				(font
					(size 0.7 0.7)
					(thickness 0.15)
				)
				(justify left bottom mirror)
			)
		)
		(fp_text user "${REFERENCE}"
			(at -0.932 -3.168 180)
			(layer "B.Fab")
			(hide yes)
			(effects
				(font
					(size 0.7 0.7)
					(thickness 0.15)
				)
				(justify left bottom mirror)
			)
		)
		(pad "1" smd roundrect
			(at -0.48 0)
			(size 0.59 0.64)
			(layers "B.Cu" "B.Paste" "B.Mask")
			(roundrect_rratio 0.25)
			(net 700 "/HDMI/DP_MUX_D3+")
			(pintype "passive")
		)
		(pad "2" smd roundrect
			(at 0.48 0)
			(size 0.59 0.64)
			(layers "B.Cu" "B.Paste" "B.Mask")
			(roundrect_rratio 0.25)
			(net 367 "DP1_TXD0_HDMI_TX2_P")
			(pintype "passive")
		)
	)
)
